(kicad_pcb
	(version 20260206)
	(generator "pcbnew")
	(generator_version "10.0")
	(general
		(thickness 1.6)
		(legacy_teardrops no)
	)
	(paper "A4")
	(title_block
		(title "baseboard — 13948-1b.1110WZS1818.brd")
		(comment 1 "Honey Badger (Wiwynn) / footprints 1472-1478 of 2523")
	)
	(layers
		(0 "F.Cu" signal "TOP")
		(4 "In1.Cu" signal "L2GND")
		(6 "In2.Cu" signal "L3")
		(8 "In3.Cu" signal "L4VCC")
		(10 "In4.Cu" signal "L5VCC")
		(12 "In5.Cu" signal "L6")
		(14 "In6.Cu" signal "L7GND")
		(2 "B.Cu" signal "BOTTOM")
		(9 "F.Adhes" user "F.Adhesive")
		(11 "B.Adhes" user "B.Adhesive")
		(13 "F.Paste" user "Package Geometry/Pastemask Top")
		(15 "B.Paste" user "Package Geometry/Pastemask Bottom")
		(5 "F.SilkS" user "Ref Des/Silkscreen Top")
		(7 "B.SilkS" user "Ref Des/Silkscreen Bottom")
		(1 "F.Mask" user "Board Geometry/Soldermask Top")
		(3 "B.Mask" user "Board Geometry/Soldermask Bottom")
		(17 "Dwgs.User" user "User.Drawings")
		(19 "Cmts.User" user "User.Comments")
		(21 "Eco1.User" user "User.Eco1")
		(23 "Eco2.User" user "User.Eco2")
		(25 "Edge.Cuts" user "Board Geometry/Outline")
		(27 "Margin" user)
		(31 "F.CrtYd" user "Package Geometry/Place Bound Top")
		(29 "B.CrtYd" user "Package Geometry/Place Bound Bottom")
		(35 "F.Fab" user "Ref Des/Assembly Top")
		(33 "B.Fab" user "Ref Des/Assembly Bottom")
	)
	(footprint ""
		(layer "F.Cu")
		(at 320.04 -141.986 90)
		(property "Reference" "D13"
			(at 0 0 90)
			(layer "F.SilkS")
			(hide yes)
			(effects
				(font
					(size 1.27 1.27)
				)
			)
		)
		(property "Value" "BAT54C-7-F-3-GP"
			(at 0 -5.0292 90)
			(unlocked yes)
			(layer "F.Fab")
			(hide yes)
			(effects
				(font
					(size 1.016 1.016)
					(thickness 0.1524)
				)
			)
		)
		(property "Device Type" "SOT23-2D4-312H48"
			(at 0 -6.5532 90)
			(unlocked yes)
			(layer "F.Fab")
			(hide yes)
			(effects
				(font
					(size 1.016 1.016)
					(thickness 0.1524)
				)
			)
		)
		(duplicate_pad_numbers_are_jumpers no)
		(fp_line
			(start 0.635 -1.778)
			(end 0.635 -0.9017)
			(stroke
				(width 0.1524)
				(type default)
			)
			(layer "F.SilkS")
		)
		(fp_line
			(start -0.635 -1.778)
			(end 0.635 -1.778)
			(stroke
				(width 0.1524)
				(type default)
			)
			(layer "F.SilkS")
		)
		(fp_line
			(start 1.7018 -0.9017)
			(end 1.7018 1.778)
			(stroke
				(width 0.1524)
				(type default)
			)
			(layer "F.SilkS")
		)
		(fp_line
			(start 0.635 -0.9017)
			(end 1.7018 -0.9017)
			(stroke
				(width 0.1524)
				(type default)
			)
			(layer "F.SilkS")
		)
		(fp_line
			(start -0.635 -0.9017)
			(end -0.635 -1.778)
			(stroke
				(width 0.1524)
				(type default)
			)
			(layer "F.SilkS")
		)
		(fp_line
			(start -1.7018 -0.9017)
			(end -0.635 -0.9017)
			(stroke
				(width 0.1524)
				(type default)
			)
			(layer "F.SilkS")
		)
		(fp_line
			(start 1.7018 1.778)
			(end -1.7018 1.778)
			(stroke
				(width 0.1524)
				(type default)
			)
			(layer "F.SilkS")
		)
		(fp_line
			(start -1.7018 1.778)
			(end -1.7018 -0.9017)
			(stroke
				(width 0.1524)
				(type default)
			)
			(layer "F.SilkS")
		)
		(fp_poly
			(pts
				(xy 0.2159 -1.1938) (xy -0.2159 -1.1938) (xy -0.2159 -0.6477) (xy -1.4478 -0.6477) (xy -1.4478 1.1938)
				(xy 1.4478 1.1938) (xy 1.4478 -0.6477) (xy 0.2159 -0.6477)
			)
			(stroke
				(width 0)
				(type default)
			)
			(fill no)
			(layer "F.CrtYd")
		)
		(fp_poly
			(pts
				(xy 1.9558 2.032) (xy 1.9558 -0.1905) (xy 1.4478 -0.1905) (xy 1.4478 1.1938) (xy -1.4478 1.1938)
				(xy -1.4478 -0.6477) (xy -0.2159 -0.6477) (xy -0.2159 -1.1938) (xy 0.2159 -1.1938) (xy 0.2159 -0.6477)
				(xy 1.4478 -0.6477) (xy 1.4478 -0.2032) (xy 1.9558 -0.2032) (xy 1.9558 -1.1557) (xy 0.889 -1.1557)
				(xy 0.889 -2.032) (xy -0.889 -2.032) (xy -0.889 -1.1557) (xy -1.9558 -1.1557) (xy -1.9558 2.032)
			)
			(stroke
				(width 0)
				(type default)
			)
			(fill no)
			(layer "F.CrtYd")
		)
		(fp_poly
			(pts
				(xy -1.9558 2.032) (xy -1.9558 -1.1557) (xy -0.889 -1.1557) (xy -0.889 -2.032) (xy 0.889 -2.032)
				(xy 0.889 -1.1557) (xy 1.9558 -1.1557) (xy 1.9558 2.032)
			)
			(stroke
				(width 0)
				(type default)
			)
			(fill no)
			(layer "F.Fab")
		)
		(pad "1" smd custom
			(at -0.98425 0.9525 90)
			(size 0.1905 0.1905)
			(layers "F.Cu" "F.Mask" "F.Paste")
			(net "P3V3_STBY")
			(options
				(clearance outline)
				(anchor circle)
			)
			(primitives
				(gr_poly
					(pts
						(arc
							(start -0.1778 0.5715)
							(mid -0.321484 0.511984)
							(end -0.381 0.3683)
						)
						(arc
							(start -0.381 -0.3683)
							(mid -0.321484 -0.511984)
							(end -0.1778 -0.5715)
						)
						(arc
							(start 0.1778 -0.5715)
							(mid 0.321484 -0.511984)
							(end 0.381 -0.3683)
						)
						(arc
							(start 0.381 0.3683)
							(mid 0.321484 0.511984)
							(end 0.1778 0.5715)
						)
					)
					(width 0)
					(fill yes)
				)
			)
		)
		(pad "2" smd custom
			(at 0.98425 0.9525 90)
			(size 0.1905 0.1905)
			(layers "F.Cu" "F.Mask" "F.Paste")
			(net "P3V0_BAT_R")
			(options
				(clearance outline)
				(anchor circle)
			)
			(primitives
				(gr_poly
					(pts
						(arc
							(start -0.1778 0.5715)
							(mid -0.321484 0.511984)
							(end -0.381 0.3683)
						)
						(arc
							(start -0.381 -0.3683)
							(mid -0.321484 -0.511984)
							(end -0.1778 -0.5715)
						)
						(arc
							(start 0.1778 -0.5715)
							(mid 0.321484 -0.511984)
							(end 0.381 -0.3683)
						)
						(arc
							(start 0.381 0.3683)
							(mid 0.321484 0.511984)
							(end 0.1778 0.5715)
						)
					)
					(width 0)
					(fill yes)
				)
			)
		)
		(pad "3" smd custom
			(at 0 -0.9525 90)
			(size 0.1905 0.1905)
			(layers "F.Cu" "F.Mask" "F.Paste")
			(net "P3V3_RTC")
			(options
				(clearance outline)
				(anchor circle)
			)
			(primitives
				(gr_poly
					(pts
						(arc
							(start -0.1778 0.5715)
							(mid -0.321484 0.511984)
							(end -0.381 0.3683)
						)
						(arc
							(start -0.381 -0.3683)
							(mid -0.321484 -0.511984)
							(end -0.1778 -0.5715)
						)
						(arc
							(start 0.1778 -0.5715)
							(mid 0.321484 -0.511984)
							(end 0.381 -0.3683)
						)
						(arc
							(start 0.381 0.3683)
							(mid 0.321484 0.511984)
							(end 0.1778 0.5715)
						)
					)
					(width 0)
					(fill yes)
				)
			)
		)
	)
	(footprint ""
		(layer "F.Cu")
		(at 81.285842 -121.864882 -90)
		(property "Reference" "SR740"
			(at 0 0 270)
			(layer "F.SilkS")
			(hide yes)
			(effects
				(font
					(size 1.27 1.27)
				)
			)
		)
		(property "Value" "2K2R2F-GP"
			(at 0.064008 -3.993896 270)
			(unlocked yes)
			(layer "F.Fab")
			(hide yes)
			(effects
				(font
					(size 1.016 1.016)
					(thickness 0.1524)
				)
			)
		)
		(property "Device Type" "R402H16"
			(at 0.064008 -5.517896 270)
			(unlocked yes)
			(layer "F.Fab")
			(hide yes)
			(effects
				(font
					(size 1.016 1.016)
					(thickness 0.1524)
				)
			)
		)
		(duplicate_pad_numbers_are_jumpers no)
		(fp_line
			(start -0.508 -0.9398)
			(end -0.508 0.9398)
			(stroke
				(width 0.1524)
				(type default)
			)
			(layer "F.SilkS")
		)
		(fp_line
			(start 0.508 -0.9398)
			(end -0.508 -0.9398)
			(stroke
				(width 0.1524)
				(type default)
			)
			(layer "F.SilkS")
		)
		(fp_rect
			(start -0.508 0.9398)
			(end 0.508 -0.9398)
			(stroke
				(width 0)
				(type default)
			)
			(fill no)
			(layer "F.CrtYd")
		)
		(fp_rect
			(start -0.508 0.9398)
			(end 0.508 -0.9398)
			(stroke
				(width 0)
				(type default)
			)
			(fill no)
			(layer "F.Fab")
		)
		(pad "1" smd custom
			(at 0 -0.4445 270)
			(size 0.1397 0.1397)
			(layers "F.Cu" "F.Mask" "F.Paste")
			(net "EXP_SCL_0")
			(options
				(clearance outline)
				(anchor circle)
			)
			(primitives
				(gr_poly
					(pts
						(arc
							(start -0.1778 -0.2794)
							(mid -0.249642 -0.249642)
							(end -0.2794 -0.1778)
						)
						(arc
							(start -0.2794 0.1778)
							(mid -0.249642 0.249642)
							(end -0.1778 0.2794)
						)
						(arc
							(start 0.1778 0.2794)
							(mid 0.249642 0.249642)
							(end 0.2794 0.1778)
						)
						(arc
							(start 0.2794 -0.1778)
							(mid 0.249642 -0.249642)
							(end 0.1778 -0.2794)
						)
					)
					(width 0)
					(fill yes)
				)
			)
		)
		(pad "2" smd custom
			(at 0 0.4445 270)
			(size 0.1397 0.1397)
			(layers "F.Cu" "F.Mask" "F.Paste")
			(net "P1V8_E")
			(options
				(clearance outline)
				(anchor circle)
			)
			(primitives
				(gr_poly
					(pts
						(arc
							(start -0.1778 -0.2794)
							(mid -0.249642 -0.249642)
							(end -0.2794 -0.1778)
						)
						(arc
							(start -0.2794 0.1778)
							(mid -0.249642 0.249642)
							(end -0.1778 0.2794)
						)
						(arc
							(start 0.1778 0.2794)
							(mid 0.249642 0.249642)
							(end 0.2794 0.1778)
						)
						(arc
							(start 0.2794 -0.1778)
							(mid 0.249642 -0.249642)
							(end 0.1778 -0.2794)
						)
					)
					(width 0)
					(fill yes)
				)
			)
		)
	)
	(footprint ""
		(layer "F.Cu")
		(at 180.35397 -67.183 180)
		(property "Reference" "C275"
			(at 0 0 180)
			(layer "F.SilkS")
			(hide yes)
			(effects
				(font
					(size 1.27 1.27)
				)
			)
		)
		(property "Value" "SCD1U25V2KX-2-GP"
			(at 1.1811 -2.7051 180)
			(unlocked yes)
			(layer "F.Fab")
			(hide yes)
			(effects
				(font
					(size 1.016 1.016)
					(thickness 0.1524)
				)
			)
		)
		(property "Device Type" "C402H22"
			(at 1.1811 -4.2291 180)
			(unlocked yes)
			(layer "F.Fab")
			(hide yes)
			(effects
				(font
					(size 1.016 1.016)
					(thickness 0.1524)
				)
			)
		)
		(duplicate_pad_numbers_are_jumpers no)
		(fp_rect
			(start -0.4318 0.9525)
			(end 0.4318 -0.9525)
			(stroke
				(width 0)
				(type default)
			)
			(fill no)
			(layer "F.CrtYd")
		)
		(fp_rect
			(start -0.4318 0.9525)
			(end 0.4318 -0.9525)
			(stroke
				(width 0)
				(type default)
			)
			(fill no)
			(layer "F.Fab")
		)
		(pad "1" smd custom
			(at 0 -0.4445 180)
			(size 0.1524 0.1524)
			(layers "F.Cu" "F.Mask" "F.Paste")
			(net "GND")
			(options
				(clearance outline)
				(anchor circle)
			)
			(primitives
				(gr_poly
					(pts
						(arc
							(start 0.3048 -0.2032)
							(mid 0.275042 -0.275042)
							(end 0.2032 -0.3048)
						)
						(arc
							(start -0.2032 -0.3048)
							(mid -0.275042 -0.275042)
							(end -0.3048 -0.2032)
						)
						(arc
							(start -0.3048 0.2032)
							(mid -0.275042 0.275042)
							(end -0.2032 0.3048)
						)
						(arc
							(start 0.2032 0.3048)
							(mid 0.275042 0.275042)
							(end 0.3048 0.2032)
						)
					)
					(width 0)
					(fill yes)
				)
			)
		)
		(pad "2" smd custom
			(at 0 0.4445 180)
			(size 0.1524 0.1524)
			(layers "F.Cu" "F.Mask" "F.Paste")
			(net "TP_MSB_B31_CPU_SATA_TX_P")
			(options
				(clearance outline)
				(anchor circle)
			)
			(primitives
				(gr_poly
					(pts
						(arc
							(start 0.3048 -0.2032)
							(mid 0.275042 -0.275042)
							(end 0.2032 -0.3048)
						)
						(arc
							(start -0.2032 -0.3048)
							(mid -0.275042 -0.275042)
							(end -0.3048 -0.2032)
						)
						(arc
							(start -0.3048 0.2032)
							(mid -0.275042 0.275042)
							(end -0.2032 0.3048)
						)
						(arc
							(start 0.2032 0.3048)
							(mid 0.275042 0.275042)
							(end 0.3048 0.2032)
						)
					)
					(width 0)
					(fill yes)
				)
			)
		)
	)
	(footprint ""
		(layer "F.Cu")
		(at 152.019 -57.785 -90)
		(property "Reference" "SR708"
			(at 0 0 270)
			(layer "F.SilkS")
			(hide yes)
			(effects
				(font
					(size 1.27 1.27)
				)
			)
		)
		(property "Value" "10KR2F-2-GP"
			(at 0.064008 -3.993896 270)
			(unlocked yes)
			(layer "F.Fab")
			(hide yes)
			(effects
				(font
					(size 1.016 1.016)
					(thickness 0.1524)
				)
			)
		)
		(property "Device Type" "R402H16"
			(at 0.064008 -5.517896 270)
			(unlocked yes)
			(layer "F.Fab")
			(hide yes)
			(effects
				(font
					(size 1.016 1.016)
					(thickness 0.1524)
				)
			)
		)
		(duplicate_pad_numbers_are_jumpers no)
		(fp_line
			(start -0.508 -0.9398)
			(end -0.508 0.9398)
			(stroke
				(width 0.1524)
				(type default)
			)
			(layer "F.SilkS")
		)
		(fp_line
			(start 0.508 -0.9398)
			(end -0.508 -0.9398)
			(stroke
				(width 0.1524)
				(type default)
			)
			(layer "F.SilkS")
		)
		(fp_rect
			(start -0.508 0.9398)
			(end 0.508 -0.9398)
			(stroke
				(width 0)
				(type default)
			)
			(fill no)
			(layer "F.CrtYd")
		)
		(fp_rect
			(start -0.508 0.9398)
			(end 0.508 -0.9398)
			(stroke
				(width 0)
				(type default)
			)
			(fill no)
			(layer "F.Fab")
		)
		(pad "1" smd custom
			(at 0 -0.4445 270)
			(size 0.1397 0.1397)
			(layers "F.Cu" "F.Mask" "F.Paste")
			(net "P1V8_C")
			(options
				(clearance outline)
				(anchor circle)
			)
			(primitives
				(gr_poly
					(pts
						(arc
							(start -0.1778 -0.2794)
							(mid -0.249642 -0.249642)
							(end -0.2794 -0.1778)
						)
						(arc
							(start -0.2794 0.1778)
							(mid -0.249642 0.249642)
							(end -0.1778 0.2794)
						)
						(arc
							(start 0.1778 0.2794)
							(mid 0.249642 0.249642)
							(end 0.2794 0.1778)
						)
						(arc
							(start 0.2794 -0.1778)
							(mid 0.249642 -0.249642)
							(end 0.1778 -0.2794)
						)
					)
					(width 0)
					(fill yes)
				)
			)
		)
		(pad "2" smd custom
			(at 0 0.4445 270)
			(size 0.1397 0.1397)
			(layers "F.Cu" "F.Mask" "F.Paste")
			(net "XM_NOR_CS_N")
			(options
				(clearance outline)
				(anchor circle)
			)
			(primitives
				(gr_poly
					(pts
						(arc
							(start -0.1778 -0.2794)
							(mid -0.249642 -0.249642)
							(end -0.2794 -0.1778)
						)
						(arc
							(start -0.2794 0.1778)
							(mid -0.249642 0.249642)
							(end -0.1778 0.2794)
						)
						(arc
							(start 0.1778 0.2794)
							(mid 0.249642 0.249642)
							(end 0.2794 0.1778)
						)
						(arc
							(start 0.2794 -0.1778)
							(mid 0.249642 -0.249642)
							(end 0.1778 -0.2794)
						)
					)
					(width 0)
					(fill yes)
				)
			)
		)
	)
	(footprint ""
		(layer "F.Cu")
		(at 63.119 -213.741 90)
		(property "Reference" "CA1"
			(at 0 0 90)
			(layer "F.SilkS")
			(hide yes)
			(effects
				(font
					(size 1.27 1.27)
				)
			)
		)
		(property "Value" "SC2D2U25V5KX-2-GP"
			(at -0.0762 -6.1214 90)
			(unlocked yes)
			(layer "F.Fab")
			(hide yes)
			(effects
				(font
					(size 1.016 1.016)
					(thickness 0.1524)
				)
			)
		)
		(property "Device Type" "C805H54"
			(at -0.0762 -8.1534 90)
			(unlocked yes)
			(layer "F.Fab")
			(hide yes)
			(effects
				(font
					(size 1.016 1.016)
					(thickness 0.1524)
				)
			)
		)
		(duplicate_pad_numbers_are_jumpers no)
		(fp_line
			(start 0.635 0)
			(end -0.635 0)
			(stroke
				(width 0.508)
				(type default)
			)
			(layer "F.SilkS")
		)
		(fp_rect
			(start -0.9652 1.778)
			(end 0.9652 -1.778)
			(stroke
				(width 0)
				(type default)
			)
			(fill no)
			(layer "F.CrtYd")
		)
		(fp_poly
			(pts
				(xy -0.9652 -1.778) (xy 0.9652 -1.778) (xy 0.9652 1.778) (xy -0.9652 1.778)
			)
			(stroke
				(width 0)
				(type default)
			)
			(fill no)
			(layer "F.Fab")
		)
		(pad "1" smd rect
			(at 0 -0.9652 90)
			(size 1.397 1.143)
			(layers "F.Cu" "F.Mask" "F.Paste")
			(net "MB0_P12V_PWRGOOD")
		)
		(pad "2" smd rect
			(at 0 0.9652 90)
			(size 1.397 1.143)
			(layers "F.Cu" "F.Mask" "F.Paste")
			(net "AGND_CURRENT_MON")
		)
	)
	(footprint ""
		(layer "F.Cu")
		(at 345.088718 -143.233648)
		(property "Reference" "C159"
			(at 0 0 0)
			(layer "F.SilkS")
			(hide yes)
			(effects
				(font
					(size 1.27 1.27)
				)
			)
		)
		(property "Value" "SC1U10V2KX-4-GP"
			(at 1.1811 -2.7051 0)
			(unlocked yes)
			(layer "F.Fab")
			(hide yes)
			(effects
				(font
					(size 1.016 1.016)
					(thickness 0.1524)
				)
			)
		)
		(property "Device Type" "C402H22"
			(at 1.1811 -4.2291 0)
			(unlocked yes)
			(layer "F.Fab")
			(hide yes)
			(effects
				(font
					(size 1.016 1.016)
					(thickness 0.1524)
				)
			)
		)
		(duplicate_pad_numbers_are_jumpers no)
		(fp_rect
			(start -0.4318 0.9525)
			(end 0.4318 -0.9525)
			(stroke
				(width 0)
				(type default)
			)
			(fill no)
			(layer "F.CrtYd")
		)
		(fp_rect
			(start -0.4318 0.9525)
			(end 0.4318 -0.9525)
			(stroke
				(width 0)
				(type default)
			)
			(fill no)
			(layer "F.Fab")
		)
		(pad "1" smd custom
			(at 0 -0.4445)
			(size 0.1524 0.1524)
			(layers "F.Cu" "F.Mask" "F.Paste")
			(net "PLLFILT")
			(options
				(clearance outline)
				(anchor circle)
			)
			(primitives
				(gr_poly
					(pts
						(arc
							(start 0.3048 -0.2032)
							(mid 0.275042 -0.275042)
							(end 0.2032 -0.3048)
						)
						(arc
							(start -0.2032 -0.3048)
							(mid -0.275042 -0.275042)
							(end -0.3048 -0.2032)
						)
						(arc
							(start -0.3048 0.2032)
							(mid -0.275042 0.275042)
							(end -0.2032 0.3048)
						)
						(arc
							(start 0.2032 0.3048)
							(mid 0.275042 0.275042)
							(end 0.3048 0.2032)
						)
					)
					(width 0)
					(fill yes)
				)
			)
		)
		(pad "2" smd custom
			(at 0 0.4445)
			(size 0.1524 0.1524)
			(layers "F.Cu" "F.Mask" "F.Paste")
			(net "GND")
			(options
				(clearance outline)
				(anchor circle)
			)
			(primitives
				(gr_poly
					(pts
						(arc
							(start 0.3048 -0.2032)
							(mid 0.275042 -0.275042)
							(end 0.2032 -0.3048)
						)
						(arc
							(start -0.2032 -0.3048)
							(mid -0.275042 -0.275042)
							(end -0.3048 -0.2032)
						)
						(arc
							(start -0.3048 0.2032)
							(mid -0.275042 0.275042)
							(end -0.2032 0.3048)
						)
						(arc
							(start 0.2032 0.3048)
							(mid 0.275042 0.275042)
							(end 0.3048 0.2032)
						)
					)
					(width 0)
					(fill yes)
				)
			)
		)
	)
	(footprint ""
		(layer "F.Cu")
		(at 79.888842 -133.269482 90)
		(property "Reference" "SC1101"
			(at 0 0 90)
			(layer "F.SilkS")
			(hide yes)
			(effects
				(font
					(size 1.27 1.27)
				)
			)
		)
		(property "Value" "SCD1U16V2KX-3GP"
			(at 1.1811 -2.7051 90)
			(unlocked yes)
			(layer "F.Fab")
			(hide yes)
			(effects
				(font
					(size 1.016 1.016)
					(thickness 0.1524)
				)
			)
		)
		(property "Device Type" "C402H22"
			(at 1.1811 -4.2291 90)
			(unlocked yes)
			(layer "F.Fab")
			(hide yes)
			(effects
				(font
					(size 1.016 1.016)
					(thickness 0.1524)
				)
			)
		)
		(duplicate_pad_numbers_are_jumpers no)
		(fp_rect
			(start -0.4318 0.9525)
			(end 0.4318 -0.9525)
			(stroke
				(width 0)
				(type default)
			)
			(fill no)
			(layer "F.CrtYd")
		)
		(fp_rect
			(start -0.4318 0.9525)
			(end 0.4318 -0.9525)
			(stroke
				(width 0)
				(type default)
			)
			(fill no)
			(layer "F.Fab")
		)
		(pad "1" smd custom
			(at 0 -0.4445 90)
			(size 0.1524 0.1524)
			(layers "F.Cu" "F.Mask" "F.Paste")
			(net "P3V3_STBY")
			(options
				(clearance outline)
				(anchor circle)
			)
			(primitives
				(gr_poly
					(pts
						(arc
							(start 0.3048 -0.2032)
							(mid 0.275042 -0.275042)
							(end 0.2032 -0.3048)
						)
						(arc
							(start -0.2032 -0.3048)
							(mid -0.275042 -0.275042)
							(end -0.3048 -0.2032)
						)
						(arc
							(start -0.3048 0.2032)
							(mid -0.275042 0.275042)
							(end -0.2032 0.3048)
						)
						(arc
							(start 0.2032 0.3048)
							(mid 0.275042 0.275042)
							(end 0.3048 0.2032)
						)
					)
					(width 0)
					(fill yes)
				)
			)
		)
		(pad "2" smd custom
			(at 0 0.4445 90)
			(size 0.1524 0.1524)
			(layers "F.Cu" "F.Mask" "F.Paste")
			(net "GND")
			(options
				(clearance outline)
				(anchor circle)
			)
			(primitives
				(gr_poly
					(pts
						(arc
							(start 0.3048 -0.2032)
							(mid 0.275042 -0.275042)
							(end 0.2032 -0.3048)
						)
						(arc
							(start -0.2032 -0.3048)
							(mid -0.275042 -0.275042)
							(end -0.3048 -0.2032)
						)
						(arc
							(start -0.3048 0.2032)
							(mid -0.275042 0.275042)
							(end -0.2032 0.3048)
						)
						(arc
							(start 0.2032 0.3048)
							(mid 0.275042 0.275042)
							(end 0.3048 0.2032)
						)
					)
					(width 0)
					(fill yes)
				)
			)
		)
	)
)
